(kicad_pcb
	(version 20260206)
	(generator "pcbnew")
	(generator_version "10.0")
	(general
		(thickness 1.6)
		(legacy_teardrops no)
	)
	(paper "A4")
	(title_block
		(title "baseboard — 13948-1b.1110WZS1818.brd")
		(comment 1 "Honey Badger (Wiwynn) / footprints 552-559 of 2523")
	)
	(layers
		(0 "F.Cu" signal "TOP")
		(4 "In1.Cu" signal "L2GND")
		(6 "In2.Cu" signal "L3")
		(8 "In3.Cu" signal "L4VCC")
		(10 "In4.Cu" signal "L5VCC")
		(12 "In5.Cu" signal "L6")
		(14 "In6.Cu" signal "L7GND")
		(2 "B.Cu" signal "BOTTOM")
		(9 "F.Adhes" user "F.Adhesive")
		(11 "B.Adhes" user "B.Adhesive")
		(13 "F.Paste" user "Package Geometry/Pastemask Top")
		(15 "B.Paste" user "Package Geometry/Pastemask Bottom")
		(5 "F.SilkS" user "Ref Des/Silkscreen Top")
		(7 "B.SilkS" user "Ref Des/Silkscreen Bottom")
		(1 "F.Mask" user "Board Geometry/Soldermask Top")
		(3 "B.Mask" user "Board Geometry/Soldermask Bottom")
		(17 "Dwgs.User" user "User.Drawings")
		(19 "Cmts.User" user "User.Comments")
		(21 "Eco1.User" user "User.Eco1")
		(23 "Eco2.User" user "User.Eco2")
		(25 "Edge.Cuts" user "Board Geometry/Outline")
		(27 "Margin" user)
		(31 "F.CrtYd" user "Package Geometry/Place Bound Top")
		(29 "B.CrtYd" user "Package Geometry/Place Bound Bottom")
		(35 "F.Fab" user "Ref Des/Assembly Top")
		(33 "B.Fab" user "Ref Des/Assembly Bottom")
	)
	(footprint ""
		(layer "F.Cu")
		(at 252.984 -126.111 -90)
		(property "Reference" "R7904"
			(at 0 0 270)
			(layer "F.SilkS")
			(hide yes)
			(effects
				(font
					(size 1.27 1.27)
				)
			)
		)
		(property "Value" "0R2J-2-GP"
			(at 0.064008 -3.993896 270)
			(unlocked yes)
			(layer "F.Fab")
			(hide yes)
			(effects
				(font
					(size 1.016 1.016)
					(thickness 0.1524)
				)
			)
		)
		(property "Device Type" "R402H16"
			(at 0.064008 -5.517896 270)
			(unlocked yes)
			(layer "F.Fab")
			(hide yes)
			(effects
				(font
					(size 1.016 1.016)
					(thickness 0.1524)
				)
			)
		)
		(duplicate_pad_numbers_are_jumpers no)
		(fp_line
			(start -0.508 -0.9398)
			(end -0.508 0.9398)
			(stroke
				(width 0.1524)
				(type default)
			)
			(layer "F.SilkS")
		)
		(fp_line
			(start 0.508 -0.9398)
			(end -0.508 -0.9398)
			(stroke
				(width 0.1524)
				(type default)
			)
			(layer "F.SilkS")
		)
		(fp_rect
			(start -0.508 0.9398)
			(end 0.508 -0.9398)
			(stroke
				(width 0)
				(type default)
			)
			(fill no)
			(layer "F.CrtYd")
		)
		(fp_rect
			(start -0.508 0.9398)
			(end 0.508 -0.9398)
			(stroke
				(width 0)
				(type default)
			)
			(fill no)
			(layer "F.Fab")
		)
		(pad "1" smd custom
			(at 0 -0.4445 270)
			(size 0.1397 0.1397)
			(layers "F.Cu" "F.Mask" "F.Paste")
			(net "CPU_U193_PIN2_TX")
			(options
				(clearance outline)
				(anchor circle)
			)
			(primitives
				(gr_poly
					(pts
						(arc
							(start -0.1778 -0.2794)
							(mid -0.249642 -0.249642)
							(end -0.2794 -0.1778)
						)
						(arc
							(start -0.2794 0.1778)
							(mid -0.249642 0.249642)
							(end -0.1778 0.2794)
						)
						(arc
							(start 0.1778 0.2794)
							(mid 0.249642 0.249642)
							(end 0.2794 0.1778)
						)
						(arc
							(start 0.2794 -0.1778)
							(mid 0.249642 -0.249642)
							(end 0.1778 -0.2794)
						)
					)
					(width 0)
					(fill yes)
				)
			)
		)
		(pad "2" smd custom
			(at 0 0.4445 270)
			(size 0.1397 0.1397)
			(layers "F.Cu" "F.Mask" "F.Paste")
			(net "CPU_TXD")
			(options
				(clearance outline)
				(anchor circle)
			)
			(primitives
				(gr_poly
					(pts
						(arc
							(start -0.1778 -0.2794)
							(mid -0.249642 -0.249642)
							(end -0.2794 -0.1778)
						)
						(arc
							(start -0.2794 0.1778)
							(mid -0.249642 0.249642)
							(end -0.1778 0.2794)
						)
						(arc
							(start 0.1778 0.2794)
							(mid 0.249642 0.249642)
							(end 0.2794 0.1778)
						)
						(arc
							(start 0.2794 -0.1778)
							(mid 0.249642 -0.249642)
							(end 0.1778 -0.2794)
						)
					)
					(width 0)
					(fill yes)
				)
			)
		)
	)
	(footprint ""
		(layer "F.Cu")
		(at 93.853 -101.854)
		(property "Reference" "STP88"
			(at 0 0 0)
			(layer "F.SilkS")
			(hide yes)
			(effects
				(font
					(size 1.27 1.27)
				)
			)
		)
		(property "Value" "TPAD28"
			(at 0.0127 -1.8034 0)
			(unlocked yes)
			(layer "F.Fab")
			(hide yes)
			(effects
				(font
					(size 1.016 1.016)
					(thickness 0.1524)
				)
			)
		)
		(property "Device Type" "TPAD28"
			(at 0.0127 -3.3274 0)
			(unlocked yes)
			(layer "F.Fab")
			(hide yes)
			(effects
				(font
					(size 1.016 1.016)
					(thickness 0.1524)
				)
			)
		)
		(duplicate_pad_numbers_are_jumpers no)
		(fp_poly
			(pts
				(arc
					(start 0.3556 0)
					(mid -0.3556 0)
					(end 0.3556 0)
				)
			)
			(stroke
				(width 0)
				(type default)
			)
			(fill no)
			(layer "F.CrtYd")
		)
		(fp_poly
			(pts
				(arc
					(start 0.6096 0)
					(mid -0.6096 0)
					(end 0.6096 0)
				)
			)
			(stroke
				(width 0)
				(type default)
			)
			(fill no)
			(layer "F.Fab")
		)
		(pad "1" smd circle
			(at 0 0)
			(size 0.7112 0.7112)
			(layers "F.Cu" "F.Mask" "F.Paste")
			(net "UART_CTS")
		)
	)
	(footprint ""
		(layer "F.Cu")
		(at 190.871856 -119.770652 -90)
		(property "Reference" "PR172"
			(at 0 0 270)
			(layer "F.SilkS")
			(hide yes)
			(effects
				(font
					(size 1.27 1.27)
				)
			)
		)
		(property "Value" "0R2J-2-GP"
			(at 0.064008 -3.993896 270)
			(unlocked yes)
			(layer "F.Fab")
			(hide yes)
			(effects
				(font
					(size 1.016 1.016)
					(thickness 0.1524)
				)
			)
		)
		(property "Device Type" "R402H16"
			(at 0.064008 -5.517896 270)
			(unlocked yes)
			(layer "F.Fab")
			(hide yes)
			(effects
				(font
					(size 1.016 1.016)
					(thickness 0.1524)
				)
			)
		)
		(duplicate_pad_numbers_are_jumpers no)
		(fp_line
			(start -0.508 -0.9398)
			(end -0.508 0.9398)
			(stroke
				(width 0.1524)
				(type default)
			)
			(layer "F.SilkS")
		)
		(fp_line
			(start 0.508 -0.9398)
			(end -0.508 -0.9398)
			(stroke
				(width 0.1524)
				(type default)
			)
			(layer "F.SilkS")
		)
		(fp_rect
			(start -0.508 0.9398)
			(end 0.508 -0.9398)
			(stroke
				(width 0)
				(type default)
			)
			(fill no)
			(layer "F.CrtYd")
		)
		(fp_rect
			(start -0.508 0.9398)
			(end 0.508 -0.9398)
			(stroke
				(width 0)
				(type default)
			)
			(fill no)
			(layer "F.Fab")
		)
		(pad "1" smd custom
			(at 0 -0.4445 270)
			(size 0.1397 0.1397)
			(layers "F.Cu" "F.Mask" "F.Paste")
			(net "P3V3_STBY_B2")
			(options
				(clearance outline)
				(anchor circle)
			)
			(primitives
				(gr_poly
					(pts
						(arc
							(start -0.1778 -0.2794)
							(mid -0.249642 -0.249642)
							(end -0.2794 -0.1778)
						)
						(arc
							(start -0.2794 0.1778)
							(mid -0.249642 0.249642)
							(end -0.1778 0.2794)
						)
						(arc
							(start 0.1778 0.2794)
							(mid 0.249642 0.249642)
							(end 0.2794 0.1778)
						)
						(arc
							(start 0.2794 -0.1778)
							(mid 0.249642 -0.249642)
							(end 0.1778 -0.2794)
						)
					)
					(width 0)
					(fill yes)
				)
			)
		)
		(pad "2" smd custom
			(at 0 0.4445 270)
			(size 0.1397 0.1397)
			(layers "F.Cu" "F.Mask" "F.Paste")
			(net "P3V3_STBY_R2")
			(options
				(clearance outline)
				(anchor circle)
			)
			(primitives
				(gr_poly
					(pts
						(arc
							(start -0.1778 -0.2794)
							(mid -0.249642 -0.249642)
							(end -0.2794 -0.1778)
						)
						(arc
							(start -0.2794 0.1778)
							(mid -0.249642 0.249642)
							(end -0.1778 0.2794)
						)
						(arc
							(start 0.1778 0.2794)
							(mid 0.249642 0.249642)
							(end 0.2794 0.1778)
						)
						(arc
							(start 0.2794 -0.1778)
							(mid 0.249642 -0.249642)
							(end 0.1778 -0.2794)
						)
					)
					(width 0)
					(fill yes)
				)
			)
		)
	)
	(footprint ""
		(layer "F.Cu")
		(at 191.897 -20.955 -90)
		(property "Reference" "R687"
			(at 0 0 270)
			(layer "F.SilkS")
			(hide yes)
			(effects
				(font
					(size 1.27 1.27)
				)
			)
		)
		(property "Value" "0R2J-2-GP"
			(at 0.064008 -3.993896 270)
			(unlocked yes)
			(layer "F.Fab")
			(hide yes)
			(effects
				(font
					(size 1.016 1.016)
					(thickness 0.1524)
				)
			)
		)
		(property "Device Type" "R402H16"
			(at 0.064008 -5.517896 270)
			(unlocked yes)
			(layer "F.Fab")
			(hide yes)
			(effects
				(font
					(size 1.016 1.016)
					(thickness 0.1524)
				)
			)
		)
		(duplicate_pad_numbers_are_jumpers no)
		(fp_line
			(start -0.508 -0.9398)
			(end -0.508 0.9398)
			(stroke
				(width 0.1524)
				(type default)
			)
			(layer "F.SilkS")
		)
		(fp_line
			(start 0.508 -0.9398)
			(end -0.508 -0.9398)
			(stroke
				(width 0.1524)
				(type default)
			)
			(layer "F.SilkS")
		)
		(fp_rect
			(start -0.508 0.9398)
			(end 0.508 -0.9398)
			(stroke
				(width 0)
				(type default)
			)
			(fill no)
			(layer "F.CrtYd")
		)
		(fp_rect
			(start -0.508 0.9398)
			(end 0.508 -0.9398)
			(stroke
				(width 0)
				(type default)
			)
			(fill no)
			(layer "F.Fab")
		)
		(pad "1" smd custom
			(at 0 -0.4445 270)
			(size 0.1397 0.1397)
			(layers "F.Cu" "F.Mask" "F.Paste")
			(net "GND")
			(options
				(clearance outline)
				(anchor circle)
			)
			(primitives
				(gr_poly
					(pts
						(arc
							(start -0.1778 -0.2794)
							(mid -0.249642 -0.249642)
							(end -0.2794 -0.1778)
						)
						(arc
							(start -0.2794 0.1778)
							(mid -0.249642 0.249642)
							(end -0.1778 0.2794)
						)
						(arc
							(start 0.1778 0.2794)
							(mid 0.249642 0.249642)
							(end 0.2794 0.1778)
						)
						(arc
							(start 0.2794 -0.1778)
							(mid 0.249642 -0.249642)
							(end 0.1778 -0.2794)
						)
					)
					(width 0)
					(fill yes)
				)
			)
		)
		(pad "2" smd custom
			(at 0 0.4445 270)
			(size 0.1397 0.1397)
			(layers "F.Cu" "F.Mask" "F.Paste")
			(net "RMII_BMC_MDIO")
			(options
				(clearance outline)
				(anchor circle)
			)
			(primitives
				(gr_poly
					(pts
						(arc
							(start -0.1778 -0.2794)
							(mid -0.249642 -0.249642)
							(end -0.2794 -0.1778)
						)
						(arc
							(start -0.2794 0.1778)
							(mid -0.249642 0.249642)
							(end -0.1778 0.2794)
						)
						(arc
							(start 0.1778 0.2794)
							(mid 0.249642 0.249642)
							(end 0.2794 0.1778)
						)
						(arc
							(start 0.2794 -0.1778)
							(mid 0.249642 -0.249642)
							(end 0.1778 -0.2794)
						)
					)
					(width 0)
					(fill yes)
				)
			)
		)
	)
	(footprint ""
		(layer "F.Cu")
		(at 48.768 -213.36 -90)
		(property "Reference" "R2172"
			(at 0 0 270)
			(layer "F.SilkS")
			(hide yes)
			(effects
				(font
					(size 1.27 1.27)
				)
			)
		)
		(property "Value" "0R2J-2-GP"
			(at 0.064008 -3.993896 270)
			(unlocked yes)
			(layer "F.Fab")
			(hide yes)
			(effects
				(font
					(size 1.016 1.016)
					(thickness 0.1524)
				)
			)
		)
		(property "Device Type" "R402H16"
			(at 0.064008 -5.517896 270)
			(unlocked yes)
			(layer "F.Fab")
			(hide yes)
			(effects
				(font
					(size 1.016 1.016)
					(thickness 0.1524)
				)
			)
		)
		(duplicate_pad_numbers_are_jumpers no)
		(fp_line
			(start -0.508 -0.9398)
			(end -0.508 0.9398)
			(stroke
				(width 0.1524)
				(type default)
			)
			(layer "F.SilkS")
		)
		(fp_line
			(start 0.508 -0.9398)
			(end -0.508 -0.9398)
			(stroke
				(width 0.1524)
				(type default)
			)
			(layer "F.SilkS")
		)
		(fp_rect
			(start -0.508 0.9398)
			(end 0.508 -0.9398)
			(stroke
				(width 0)
				(type default)
			)
			(fill no)
			(layer "F.CrtYd")
		)
		(fp_rect
			(start -0.508 0.9398)
			(end 0.508 -0.9398)
			(stroke
				(width 0)
				(type default)
			)
			(fill no)
			(layer "F.Fab")
		)
		(pad "1" smd custom
			(at 0 -0.4445 270)
			(size 0.1397 0.1397)
			(layers "F.Cu" "F.Mask" "F.Paste")
			(net "MB0_CM_ADR2_R")
			(options
				(clearance outline)
				(anchor circle)
			)
			(primitives
				(gr_poly
					(pts
						(arc
							(start -0.1778 -0.2794)
							(mid -0.249642 -0.249642)
							(end -0.2794 -0.1778)
						)
						(arc
							(start -0.2794 0.1778)
							(mid -0.249642 0.249642)
							(end -0.1778 0.2794)
						)
						(arc
							(start 0.1778 0.2794)
							(mid 0.249642 0.249642)
							(end 0.2794 0.1778)
						)
						(arc
							(start 0.2794 -0.1778)
							(mid 0.249642 -0.249642)
							(end 0.1778 -0.2794)
						)
					)
					(width 0)
					(fill yes)
				)
			)
		)
		(pad "2" smd custom
			(at 0 0.4445 270)
			(size 0.1397 0.1397)
			(layers "F.Cu" "F.Mask" "F.Paste")
			(net "AGND_CURRENT_MON")
			(options
				(clearance outline)
				(anchor circle)
			)
			(primitives
				(gr_poly
					(pts
						(arc
							(start -0.1778 -0.2794)
							(mid -0.249642 -0.249642)
							(end -0.2794 -0.1778)
						)
						(arc
							(start -0.2794 0.1778)
							(mid -0.249642 0.249642)
							(end -0.1778 0.2794)
						)
						(arc
							(start 0.1778 0.2794)
							(mid 0.249642 0.249642)
							(end 0.2794 0.1778)
						)
						(arc
							(start 0.2794 -0.1778)
							(mid 0.249642 -0.249642)
							(end 0.1778 -0.2794)
						)
					)
					(width 0)
					(fill yes)
				)
			)
		)
	)
	(footprint ""
		(layer "F.Cu")
		(at 180.721 -17.78)
		(property "Reference" "C153"
			(at 0 0 0)
			(layer "F.SilkS")
			(hide yes)
			(effects
				(font
					(size 1.27 1.27)
				)
			)
		)
		(property "Value" "SC100P50V2JN-3GP"
			(at 1.1811 -2.7051 0)
			(unlocked yes)
			(layer "F.Fab")
			(hide yes)
			(effects
				(font
					(size 1.016 1.016)
					(thickness 0.1524)
				)
			)
		)
		(property "Device Type" "C402H22"
			(at 1.1811 -4.2291 0)
			(unlocked yes)
			(layer "F.Fab")
			(hide yes)
			(effects
				(font
					(size 1.016 1.016)
					(thickness 0.1524)
				)
			)
		)
		(duplicate_pad_numbers_are_jumpers no)
		(fp_rect
			(start -0.4318 0.9525)
			(end 0.4318 -0.9525)
			(stroke
				(width 0)
				(type default)
			)
			(fill no)
			(layer "F.CrtYd")
		)
		(fp_rect
			(start -0.4318 0.9525)
			(end 0.4318 -0.9525)
			(stroke
				(width 0)
				(type default)
			)
			(fill no)
			(layer "F.Fab")
		)
		(pad "1" smd custom
			(at 0 -0.4445)
			(size 0.1524 0.1524)
			(layers "F.Cu" "F.Mask" "F.Paste")
			(net "TEMP_SENSOR_DXP")
			(options
				(clearance outline)
				(anchor circle)
			)
			(primitives
				(gr_poly
					(pts
						(arc
							(start 0.3048 -0.2032)
							(mid 0.275042 -0.275042)
							(end 0.2032 -0.3048)
						)
						(arc
							(start -0.2032 -0.3048)
							(mid -0.275042 -0.275042)
							(end -0.3048 -0.2032)
						)
						(arc
							(start -0.3048 0.2032)
							(mid -0.275042 0.275042)
							(end -0.2032 0.3048)
						)
						(arc
							(start 0.2032 0.3048)
							(mid 0.275042 0.275042)
							(end 0.3048 0.2032)
						)
					)
					(width 0)
					(fill yes)
				)
			)
		)
		(pad "2" smd custom
			(at 0 0.4445)
			(size 0.1524 0.1524)
			(layers "F.Cu" "F.Mask" "F.Paste")
			(net "TEMP_SENSOR_DXN")
			(options
				(clearance outline)
				(anchor circle)
			)
			(primitives
				(gr_poly
					(pts
						(arc
							(start 0.3048 -0.2032)
							(mid 0.275042 -0.275042)
							(end 0.2032 -0.3048)
						)
						(arc
							(start -0.2032 -0.3048)
							(mid -0.275042 -0.275042)
							(end -0.3048 -0.2032)
						)
						(arc
							(start -0.3048 0.2032)
							(mid -0.275042 0.275042)
							(end -0.2032 0.3048)
						)
						(arc
							(start 0.2032 0.3048)
							(mid 0.275042 0.275042)
							(end 0.3048 0.2032)
						)
					)
					(width 0)
					(fill yes)
				)
			)
		)
	)
	(footprint ""
		(layer "F.Cu")
		(at 24.580088 -195.454016 180)
		(property "Reference" "SR269"
			(at 0 0 180)
			(layer "F.SilkS")
			(hide yes)
			(effects
				(font
					(size 1.27 1.27)
				)
			)
		)
		(property "Value" "4K7R2F-GP"
			(at 0.064008 -3.993896 180)
			(unlocked yes)
			(layer "F.Fab")
			(hide yes)
			(effects
				(font
					(size 1.016 1.016)
					(thickness 0.1524)
				)
			)
		)
		(property "Device Type" "R402H16"
			(at 0.064008 -5.517896 180)
			(unlocked yes)
			(layer "F.Fab")
			(hide yes)
			(effects
				(font
					(size 1.016 1.016)
					(thickness 0.1524)
				)
			)
		)
		(duplicate_pad_numbers_are_jumpers no)
		(fp_line
			(start 0.508 -0.9398)
			(end -0.508 -0.9398)
			(stroke
				(width 0.1524)
				(type default)
			)
			(layer "F.SilkS")
		)
		(fp_line
			(start -0.508 -0.9398)
			(end -0.508 0.9398)
			(stroke
				(width 0.1524)
				(type default)
			)
			(layer "F.SilkS")
		)
		(fp_rect
			(start -0.508 0.9398)
			(end 0.508 -0.9398)
			(stroke
				(width 0)
				(type default)
			)
			(fill no)
			(layer "F.CrtYd")
		)
		(fp_rect
			(start -0.508 0.9398)
			(end 0.508 -0.9398)
			(stroke
				(width 0)
				(type default)
			)
			(fill no)
			(layer "F.Fab")
		)
		(pad "1" smd custom
			(at 0 -0.4445 180)
			(size 0.1397 0.1397)
			(layers "F.Cu" "F.Mask" "F.Paste")
			(net "P1V8_E")
			(options
				(clearance outline)
				(anchor circle)
			)
			(primitives
				(gr_poly
					(pts
						(arc
							(start -0.1778 -0.2794)
							(mid -0.249642 -0.249642)
							(end -0.2794 -0.1778)
						)
						(arc
							(start -0.2794 0.1778)
							(mid -0.249642 0.249642)
							(end -0.1778 0.2794)
						)
						(arc
							(start 0.1778 0.2794)
							(mid 0.249642 0.249642)
							(end 0.2794 0.1778)
						)
						(arc
							(start 0.2794 -0.1778)
							(mid 0.249642 -0.249642)
							(end 0.1778 -0.2794)
						)
					)
					(width 0)
					(fill yes)
				)
			)
		)
		(pad "2" smd custom
			(at 0 0.4445 180)
			(size 0.1397 0.1397)
			(layers "F.Cu" "F.Mask" "F.Paste")
			(net "I2C_IO_EXP_RESET#_PRST")
			(options
				(clearance outline)
				(anchor circle)
			)
			(primitives
				(gr_poly
					(pts
						(arc
							(start -0.1778 -0.2794)
							(mid -0.249642 -0.249642)
							(end -0.2794 -0.1778)
						)
						(arc
							(start -0.2794 0.1778)
							(mid -0.249642 0.249642)
							(end -0.1778 0.2794)
						)
						(arc
							(start 0.1778 0.2794)
							(mid 0.249642 0.249642)
							(end 0.2794 0.1778)
						)
						(arc
							(start 0.2794 -0.1778)
							(mid 0.249642 -0.249642)
							(end 0.1778 -0.2794)
						)
					)
					(width 0)
					(fill yes)
				)
			)
		)
	)
	(footprint ""
		(layer "F.Cu")
		(at 140.716 -38.862 180)
		(property "Reference" "SR694"
			(at 0 0 180)
			(layer "F.SilkS")
			(hide yes)
			(effects
				(font
					(size 1.27 1.27)
				)
			)
		)
		(property "Value" "10KR2F-2-GP"
			(at 0.064008 -3.993896 180)
			(unlocked yes)
			(layer "F.Fab")
			(hide yes)
			(effects
				(font
					(size 1.016 1.016)
					(thickness 0.1524)
				)
			)
		)
		(property "Device Type" "R402H16"
			(at 0.064008 -5.517896 180)
			(unlocked yes)
			(layer "F.Fab")
			(hide yes)
			(effects
				(font
					(size 1.016 1.016)
					(thickness 0.1524)
				)
			)
		)
		(duplicate_pad_numbers_are_jumpers no)
		(fp_line
			(start 0.508 -0.9398)
			(end -0.508 -0.9398)
			(stroke
				(width 0.1524)
				(type default)
			)
			(layer "F.SilkS")
		)
		(fp_line
			(start -0.508 -0.9398)
			(end -0.508 0.9398)
			(stroke
				(width 0.1524)
				(type default)
			)
			(layer "F.SilkS")
		)
		(fp_rect
			(start -0.508 0.9398)
			(end 0.508 -0.9398)
			(stroke
				(width 0)
				(type default)
			)
			(fill no)
			(layer "F.CrtYd")
		)
		(fp_rect
			(start -0.508 0.9398)
			(end 0.508 -0.9398)
			(stroke
				(width 0)
				(type default)
			)
			(fill no)
			(layer "F.Fab")
		)
		(pad "1" smd custom
			(at 0 -0.4445 180)
			(size 0.1397 0.1397)
			(layers "F.Cu" "F.Mask" "F.Paste")
			(net "P1V8_C")
			(options
				(clearance outline)
				(anchor circle)
			)
			(primitives
				(gr_poly
					(pts
						(arc
							(start -0.1778 -0.2794)
							(mid -0.249642 -0.249642)
							(end -0.2794 -0.1778)
						)
						(arc
							(start -0.2794 0.1778)
							(mid -0.249642 0.249642)
							(end -0.1778 0.2794)
						)
						(arc
							(start 0.1778 0.2794)
							(mid 0.249642 0.249642)
							(end 0.2794 0.1778)
						)
						(arc
							(start 0.2794 -0.1778)
							(mid 0.249642 -0.249642)
							(end 0.1778 -0.2794)
						)
					)
					(width 0)
					(fill yes)
				)
			)
		)
		(pad "2" smd custom
			(at 0 0.4445 180)
			(size 0.1397 0.1397)
			(layers "F.Cu" "F.Mask" "F.Paste")
			(net "XM_WE_N")
			(options
				(clearance outline)
				(anchor circle)
			)
			(primitives
				(gr_poly
					(pts
						(arc
							(start -0.1778 -0.2794)
							(mid -0.249642 -0.249642)
							(end -0.2794 -0.1778)
						)
						(arc
							(start -0.2794 0.1778)
							(mid -0.249642 0.249642)
							(end -0.1778 0.2794)
						)
						(arc
							(start 0.1778 0.2794)
							(mid 0.249642 0.249642)
							(end 0.2794 0.1778)
						)
						(arc
							(start 0.2794 -0.1778)
							(mid 0.249642 -0.249642)
							(end 0.1778 -0.2794)
						)
					)
					(width 0)
					(fill yes)
				)
			)
		)
	)
)
